# BASEBOARD_FAB2 (Tioga Pass) — schematic netlist excerpt (pin names and nets, part order shuffled) for the footprints in the layout excerpt that follows; sources: Cadence DE-HDL packaged netlist, KiCad conversion of Wiwynn_Tioga_Pass_MB.brd

R8F14  RES  4.75K 1% CHIP  pkg 0402  page 162 : A = P3V3_STBY ; B = PU_SPI_BMC_BT_HOLD_N
C2U1  CAP  10UF 16V 10% X6S  pkg 0805  page 198 : A = P3V3_STBY ; B = GND
R9G4  RES  0.0 5% CHIP  pkg 0402  page 141 : A = NIC_LED_ACT_ANODE_R ; B = P3V3_STBY

(kicad_pcb
	(version 20260206)
	(generator "pcbnew")
	(generator_version "10.0")
	(general
		(thickness 1.6)
		(legacy_teardrops no)
	)
	(paper "A4")
	(title_block
		(title "Wiwynn_Tioga_Pass_MB.brd")
		(comment 1 "Tioga Pass / footprints 3477-3479 of 4770")
	)
	(layers
		(0 "F.Cu" signal "TOP")
		(4 "In1.Cu" signal "L2GND")
		(6 "In2.Cu" signal "L3")
		(8 "In3.Cu" signal "L4GND")
		(10 "In4.Cu" signal "L5")
		(12 "In5.Cu" signal "L6GND")
		(14 "In6.Cu" signal "L7VCC")
		(16 "In7.Cu" signal "L8VCC")
		(18 "In8.Cu" signal "L9GND")
		(20 "In9.Cu" signal "L10")
		(22 "In10.Cu" signal "L11GND")
		(24 "In11.Cu" signal "L12")
		(26 "In12.Cu" signal "L13GND")
		(2 "B.Cu" signal "BOTTOM")
		(9 "F.Adhes" user "F.Adhesive")
		(11 "B.Adhes" user "B.Adhesive")
		(13 "F.Paste" user "Package Geometry/Pastemask Top")
		(15 "B.Paste" user "Package Geometry/Pastemask Bottom")
		(5 "F.SilkS" user "Ref Des/Silkscreen Top")
		(7 "B.SilkS" user "Ref Des/Silkscreen Bottom")
		(1 "F.Mask" user "Board Geometry/Soldermask Top")
		(3 "B.Mask" user "Board Geometry/Soldermask Bottom")
		(17 "Dwgs.User" user "User.Drawings")
		(19 "Cmts.User" user "User.Comments")
		(21 "Eco1.User" user "User.Eco1")
		(23 "Eco2.User" user "User.Eco2")
		(25 "Edge.Cuts" user "Board Geometry/Outline")
		(27 "Margin" user)
		(31 "F.CrtYd" user "Package Geometry/Place Bound Top")
		(29 "B.CrtYd" user "Package Geometry/Place Bound Bottom")
		(35 "F.Fab" user "Ref Des/Assembly Top")
		(33 "B.Fab" user "Ref Des/Assembly Bottom")
	)
	(footprint ""
		(layer "B.Cu")
		(at 367.157 -40.5892 180)
		(property "Reference" "R8F14"
			(at 0 0 0)
			(layer "B.SilkS")
			(hide yes)
			(effects
				(font
					(size 1.27 1.27)
				)
				(justify mirror)
			)
		)
		(property "Value" ""
			(at 0 0 0)
			(layer "B.Fab")
			(effects
				(font
					(size 1.27 1.27)
				)
				(justify mirror)
			)
		)
		(duplicate_pad_numbers_are_jumpers no)
		(fp_poly
			(pts
				(xy 0.2794 -0.1016) (xy -0.2794 -0.1016) (xy -0.2794 0.9906) (xy 0.2794 0.9906)
			)
			(stroke
				(width 0)
				(type default)
			)
			(fill no)
			(layer "B.CrtYd")
		)
		(fp_line
			(start 0.2794 0.9906)
			(end -0.2794 0.9906)
			(stroke
				(width 0.1)
				(type default)
			)
			(layer "B.Fab")
		)
		(fp_line
			(start 0.2794 -0.1016)
			(end 0.2794 0.9906)
			(stroke
				(width 0.1)
				(type default)
			)
			(layer "B.Fab")
		)
		(fp_line
			(start -0.2794 0.9906)
			(end -0.2794 -0.1016)
			(stroke
				(width 0.1)
				(type default)
			)
			(layer "B.Fab")
		)
		(fp_line
			(start -0.2794 -0.1016)
			(end 0.2794 -0.1016)
			(stroke
				(width 0.1)
				(type default)
			)
			(layer "B.Fab")
		)
		(pad "1" smd rect
			(at 0 0)
			(size 0.508 0.508)
			(layers "B.Cu" "B.Mask" "B.Paste")
			(net "P3V3_STBY")
		)
		(pad "2" smd rect
			(at 0 0.889)
			(size 0.508 0.508)
			(layers "B.Cu" "B.Mask" "B.Paste")
			(net "PU_SPI_BMC_BT_HOLD_N")
		)
		(zone
			(layer "B.Cu")
			(hatch none 0.5)
			(connect_pads
				(clearance 0)
			)
			(min_thickness 0.25)
			(keepout
				(tracks not_allowed)
				(vias allowed)
				(pads allowed)
				(copperpour not_allowed)
				(footprints allowed)
			)
			(placement
				(enabled no)
				(sheetname "")
			)
			(fill
				(thermal_gap 0.5)
				(thermal_bridge_width 0.5)
				(island_removal_mode 0)
			)
			(polygon
				(pts
					(xy 366.903 -41.2242) (xy 367.411 -41.2242) (xy 367.411 -40.8432) (xy 366.903 -40.8432)
				)
			)
		)
		(zone
			(layer "B.Cu")
			(hatch none 0.5)
			(connect_pads
				(clearance 0)
			)
			(min_thickness 0.25)
			(keepout
				(tracks allowed)
				(vias not_allowed)
				(pads allowed)
				(copperpour not_allowed)
				(footprints allowed)
			)
			(placement
				(enabled no)
				(sheetname "")
			)
			(fill
				(thermal_gap 0.5)
				(thermal_bridge_width 0.5)
				(island_removal_mode 0)
			)
			(polygon
				(pts
					(xy 366.903 -40.8432) (xy 367.411 -40.8432) (xy 367.411 -41.2242) (xy 366.903 -41.2242)
				)
			)
		)
	)
	(footprint ""
		(layer "B.Cu")
		(at 463.492088 -11.993372 -90)
		(property "Reference" "C2U1"
			(at 0 0 90)
			(layer "B.SilkS")
			(hide yes)
			(effects
				(font
					(size 1.27 1.27)
				)
				(justify mirror)
			)
		)
		(property "Value" ""
			(at 0 0 90)
			(layer "B.Fab")
			(effects
				(font
					(size 1.27 1.27)
				)
				(justify mirror)
			)
		)
		(duplicate_pad_numbers_are_jumpers no)
		(fp_rect
			(start -0.7239 1.9939)
			(end 0.7239 -0.2159)
			(stroke
				(width 0)
				(type default)
			)
			(fill no)
			(layer "B.CrtYd")
		)
		(fp_line
			(start -0.7239 1.9939)
			(end -0.7239 -0.2159)
			(stroke
				(width 0.1)
				(type default)
			)
			(layer "B.Fab")
		)
		(fp_line
			(start 0.7239 1.9939)
			(end -0.7239 1.9939)
			(stroke
				(width 0.1)
				(type default)
			)
			(layer "B.Fab")
		)
		(fp_line
			(start -0.7239 -0.2159)
			(end 0.7239 -0.2159)
			(stroke
				(width 0.1)
				(type default)
			)
			(layer "B.Fab")
		)
		(fp_line
			(start 0.7239 -0.2159)
			(end 0.7239 1.9939)
			(stroke
				(width 0.1)
				(type default)
			)
			(layer "B.Fab")
		)
		(pad "1" smd rect
			(at 0 0 90)
			(size 1.27 1.016)
			(layers "B.Cu" "B.Mask" "B.Paste")
			(net "P3V3_STBY")
		)
		(pad "2" smd rect
			(at 0 1.778 90)
			(size 1.27 1.016)
			(layers "B.Cu" "B.Mask" "B.Paste")
			(net "GND")
		)
		(zone
			(layer "B.Cu")
			(hatch none 0.5)
			(connect_pads
				(clearance 0)
			)
			(min_thickness 0.25)
			(keepout
				(tracks not_allowed)
				(vias allowed)
				(pads allowed)
				(copperpour not_allowed)
				(footprints allowed)
			)
			(placement
				(enabled no)
				(sheetname "")
			)
			(fill
				(thermal_gap 0.5)
				(thermal_bridge_width 0.5)
				(island_removal_mode 0)
			)
			(polygon
				(pts
					(xy 462.222088 -12.628372) (xy 462.222088 -11.358372) (xy 462.984088 -11.358372) (xy 462.984088 -12.628372)
				)
			)
		)
	)
	(footprint ""
		(layer "B.Cu")
		(at 485.049322 4.971288 90)
		(property "Reference" "R9G4"
			(at 0 0 90)
			(layer "B.SilkS")
			(hide yes)
			(effects
				(font
					(size 1.27 1.27)
				)
				(justify mirror)
			)
		)
		(property "Value" ""
			(at 0 0 90)
			(layer "B.Fab")
			(effects
				(font
					(size 1.27 1.27)
				)
				(justify mirror)
			)
		)
		(duplicate_pad_numbers_are_jumpers no)
		(fp_poly
			(pts
				(xy 0.2794 -0.1016) (xy -0.2794 -0.1016) (xy -0.2794 0.9906) (xy 0.2794 0.9906)
			)
			(stroke
				(width 0)
				(type default)
			)
			(fill no)
			(layer "B.CrtYd")
		)
		(fp_line
			(start 0.2794 -0.1016)
			(end 0.2794 0.9906)
			(stroke
				(width 0.1)
				(type default)
			)
			(layer "B.Fab")
		)
		(fp_line
			(start -0.2794 -0.1016)
			(end 0.2794 -0.1016)
			(stroke
				(width 0.1)
				(type default)
			)
			(layer "B.Fab")
		)
		(fp_line
			(start 0.2794 0.9906)
			(end -0.2794 0.9906)
			(stroke
				(width 0.1)
				(type default)
			)
			(layer "B.Fab")
		)
		(fp_line
			(start -0.2794 0.9906)
			(end -0.2794 -0.1016)
			(stroke
				(width 0.1)
				(type default)
			)
			(layer "B.Fab")
		)
		(pad "1" smd rect
			(at 0 0 270)
			(size 0.508 0.508)
			(layers "B.Cu" "B.Mask" "B.Paste")
			(net "NIC_LED_ACT_ANODE_R")
		)
		(pad "2" smd rect
			(at 0 0.889 270)
			(size 0.508 0.508)
			(layers "B.Cu" "B.Mask" "B.Paste")
			(net "P3V3_STBY")
		)
		(zone
			(layer "B.Cu")
			(hatch none 0.5)
			(connect_pads
				(clearance 0)
			)
			(min_thickness 0.25)
			(keepout
				(tracks allowed)
				(vias not_allowed)
				(pads allowed)
				(copperpour not_allowed)
				(footprints allowed)
			)
			(placement
				(enabled no)
				(sheetname "")
			)
			(fill
				(thermal_gap 0.5)
				(thermal_bridge_width 0.5)
				(island_removal_mode 0)
			)
			(polygon
				(pts
					(xy 485.303322 4.717288) (xy 485.303322 5.225288) (xy 485.684322 5.225288) (xy 485.684322 4.717288)
				)
			)
		)
		(zone
			(layer "B.Cu")
			(hatch none 0.5)
			(connect_pads
				(clearance 0)
			)
			(min_thickness 0.25)
			(keepout
				(tracks not_allowed)
				(vias allowed)
				(pads allowed)
				(copperpour not_allowed)
				(footprints allowed)
			)
			(placement
				(enabled no)
				(sheetname "")
			)
			(fill
				(thermal_gap 0.5)
				(thermal_bridge_width 0.5)
				(island_removal_mode 0)
			)
			(polygon
				(pts
					(xy 485.684322 4.717288) (xy 485.684322 5.225288) (xy 485.303322 5.225288) (xy 485.303322 4.717288)
				)
			)
		)
	)
)
